# BASEBOARD_FAB2 (Tioga Pass) — schematic netlist excerpt (pin names and nets, part order shuffled) for the footprints in the layout excerpt that follows; sources: Cadence DE-HDL packaged netlist, KiCad conversion of Wiwynn_Tioga_Pass_MB.brd

C22W11  SC22U16V5MX-4-GP  20%  pkg SMD-BCG5  page 240 : \1\ = VR_FET_SW_P12V_STBY_P3V3_STBY ; \2\ = GND
R9F31  5K1R2F-2-GP  1%  pkg SMD-RG  page 239 : \1\ = P1V2_AUX_BMC ; \2\ = VR_P1V2_BMC_STBY_FB
C1B4  CAP  1000PF 50V 10% X7R  pkg 0402LF  page 226 : A = PWRGD_PVDDQ_KLM_R ; B = GND

(kicad_pcb
	(version 20260206)
	(generator "pcbnew")
	(generator_version "10.0")
	(general
		(thickness 1.6)
		(legacy_teardrops no)
	)
	(paper "A4")
	(title_block
		(title "Wiwynn_Tioga_Pass_MB.brd")
		(comment 1 "Tioga Pass / footprints 1943-1945 of 4770")
	)
	(layers
		(0 "F.Cu" signal "TOP")
		(4 "In1.Cu" signal "L2GND")
		(6 "In2.Cu" signal "L3")
		(8 "In3.Cu" signal "L4GND")
		(10 "In4.Cu" signal "L5")
		(12 "In5.Cu" signal "L6GND")
		(14 "In6.Cu" signal "L7VCC")
		(16 "In7.Cu" signal "L8VCC")
		(18 "In8.Cu" signal "L9GND")
		(20 "In9.Cu" signal "L10")
		(22 "In10.Cu" signal "L11GND")
		(24 "In11.Cu" signal "L12")
		(26 "In12.Cu" signal "L13GND")
		(2 "B.Cu" signal "BOTTOM")
		(9 "F.Adhes" user "F.Adhesive")
		(11 "B.Adhes" user "B.Adhesive")
		(13 "F.Paste" user "Package Geometry/Pastemask Top")
		(15 "B.Paste" user "Package Geometry/Pastemask Bottom")
		(5 "F.SilkS" user "Ref Des/Silkscreen Top")
		(7 "B.SilkS" user "Ref Des/Silkscreen Bottom")
		(1 "F.Mask" user "Board Geometry/Soldermask Top")
		(3 "B.Mask" user "Board Geometry/Soldermask Bottom")
		(17 "Dwgs.User" user "User.Drawings")
		(19 "Cmts.User" user "User.Comments")
		(21 "Eco1.User" user "User.Eco1")
		(23 "Eco2.User" user "User.Eco2")
		(25 "Edge.Cuts" user "Board Geometry/Outline")
		(27 "Margin" user)
		(31 "F.CrtYd" user "Package Geometry/Place Bound Top")
		(29 "B.CrtYd" user "Package Geometry/Place Bound Bottom")
		(35 "F.Fab" user "Ref Des/Assembly Top")
		(33 "B.Fab" user "Ref Des/Assembly Bottom")
	)
	(footprint ""
		(layer "F.Cu")
		(at 471.338402 -36.562792 180)
		(property "Reference" "R9F31"
			(at 0 0 180)
			(layer "F.SilkS")
			(hide yes)
			(effects
				(font
					(size 1.27 1.27)
				)
			)
		)
		(property "Value" "*"
			(at 0.064008 -4.108196 180)
			(unlocked yes)
			(layer "F.Fab")
			(hide yes)
			(effects
				(font
					(size 1.27 1.016)
					(thickness 0.1524)
				)
			)
		)
		(property "Device Type" "5K1R2F-2-GP_SMD-RG-5K1R2F-2-GPA"
			(at 0.064008 -5.632196 180)
			(unlocked yes)
			(layer "F.Fab")
			(hide yes)
			(effects
				(font
					(size 1.27 1.016)
					(thickness 0.1524)
				)
			)
		)
		(duplicate_pad_numbers_are_jumpers no)
		(fp_line
			(start 0.508 -0.9398)
			(end -0.508 -0.9398)
			(stroke
				(width 0.1524)
				(type default)
			)
			(layer "F.SilkS")
		)
		(fp_line
			(start -0.508 -0.9398)
			(end -0.508 0.9398)
			(stroke
				(width 0.1524)
				(type default)
			)
			(layer "F.SilkS")
		)
		(fp_rect
			(start -0.508 0.9398)
			(end 0.508 -0.9398)
			(stroke
				(width 0)
				(type default)
			)
			(fill no)
			(layer "F.CrtYd")
		)
		(fp_rect
			(start -0.508 0.9398)
			(end 0.508 -0.9398)
			(stroke
				(width 0)
				(type default)
			)
			(fill no)
			(layer "F.Fab")
		)
		(pad "1" smd custom
			(at 0 -0.4445 180)
			(size 0.1397 0.1397)
			(layers "F.Cu" "F.Mask" "F.Paste")
			(net "P1V2_AUX_BMC")
			(options
				(clearance outline)
				(anchor circle)
			)
			(primitives
				(gr_poly
					(pts
						(arc
							(start -0.1778 -0.2794)
							(mid -0.249642 -0.249642)
							(end -0.2794 -0.1778)
						)
						(arc
							(start -0.2794 0.1778)
							(mid -0.249642 0.249642)
							(end -0.1778 0.2794)
						)
						(arc
							(start 0.1778 0.2794)
							(mid 0.249642 0.249642)
							(end 0.2794 0.1778)
						)
						(arc
							(start 0.2794 -0.1778)
							(mid 0.249642 -0.249642)
							(end 0.1778 -0.2794)
						)
					)
					(width 0)
					(fill yes)
				)
			)
		)
		(pad "2" smd custom
			(at 0 0.4445 180)
			(size 0.1397 0.1397)
			(layers "F.Cu" "F.Mask" "F.Paste")
			(net "VR_P1V2_BMC_STBY_FB")
			(options
				(clearance outline)
				(anchor circle)
			)
			(primitives
				(gr_poly
					(pts
						(arc
							(start -0.1778 -0.2794)
							(mid -0.249642 -0.249642)
							(end -0.2794 -0.1778)
						)
						(arc
							(start -0.2794 0.1778)
							(mid -0.249642 0.249642)
							(end -0.1778 0.2794)
						)
						(arc
							(start 0.1778 0.2794)
							(mid 0.249642 0.249642)
							(end 0.2794 0.1778)
						)
						(arc
							(start 0.2794 -0.1778)
							(mid 0.249642 -0.249642)
							(end 0.1778 -0.2794)
						)
					)
					(width 0)
					(fill yes)
				)
			)
		)
	)
	(footprint ""
		(layer "F.Cu")
		(at 0.18034 -131.67106 180)
		(property "Reference" "C1B4"
			(at 0 0 180)
			(layer "F.SilkS")
			(hide yes)
			(effects
				(font
					(size 1.27 1.27)
				)
			)
		)
		(property "Value" ""
			(at 0 0 180)
			(layer "F.Fab")
			(effects
				(font
					(size 1.27 1.27)
				)
			)
		)
		(duplicate_pad_numbers_are_jumpers no)
		(fp_poly
			(pts
				(xy 0.3048 -0.1016) (xy 0.3048 0.9906) (xy -0.3048 0.9906) (xy -0.3048 -0.1016)
			)
			(stroke
				(width 0)
				(type default)
			)
			(fill no)
			(layer "F.CrtYd")
		)
		(fp_line
			(start 0.3048 0.9906)
			(end 0.3048 -0.1016)
			(stroke
				(width 0.1)
				(type default)
			)
			(layer "F.Fab")
		)
		(fp_line
			(start 0.3048 -0.1016)
			(end -0.3048 -0.1016)
			(stroke
				(width 0.1)
				(type default)
			)
			(layer "F.Fab")
		)
		(fp_line
			(start -0.3048 0.9906)
			(end 0.3048 0.9906)
			(stroke
				(width 0.1)
				(type default)
			)
			(layer "F.Fab")
		)
		(fp_line
			(start -0.3048 -0.1016)
			(end -0.3048 0.9906)
			(stroke
				(width 0.1)
				(type default)
			)
			(layer "F.Fab")
		)
		(pad "1" smd rect
			(at 0 0 180)
			(size 0.508 0.508)
			(layers "F.Cu" "F.Mask" "F.Paste")
			(net "PWRGD_PVDDQ_KLM_R")
		)
		(pad "2" smd rect
			(at 0 0.889 180)
			(size 0.508 0.508)
			(layers "F.Cu" "F.Mask" "F.Paste")
			(net "GND")
		)
		(zone
			(layer "F.Cu")
			(hatch none 0.5)
			(connect_pads
				(clearance 0)
			)
			(min_thickness 0.25)
			(keepout
				(tracks not_allowed)
				(vias allowed)
				(pads allowed)
				(copperpour not_allowed)
				(footprints allowed)
			)
			(placement
				(enabled no)
				(sheetname "")
			)
			(fill
				(thermal_gap 0.5)
				(thermal_bridge_width 0.5)
				(island_removal_mode 0)
			)
			(polygon
				(pts
					(xy 0.43434 -132.30606) (xy -0.07366 -132.30606) (xy -0.07366 -131.92506) (xy 0.43434 -131.92506)
				)
			)
		)
		(zone
			(layer "F.Cu")
			(hatch none 0.5)
			(connect_pads
				(clearance 0)
			)
			(min_thickness 0.25)
			(keepout
				(tracks allowed)
				(vias not_allowed)
				(pads allowed)
				(copperpour not_allowed)
				(footprints allowed)
			)
			(placement
				(enabled no)
				(sheetname "")
			)
			(fill
				(thermal_gap 0.5)
				(thermal_bridge_width 0.5)
				(island_removal_mode 0)
			)
			(polygon
				(pts
					(xy 0.43434 -131.92506) (xy -0.07366 -131.92506) (xy -0.07366 -132.30606) (xy 0.43434 -132.30606)
				)
			)
		)
	)
	(footprint ""
		(layer "F.Cu")
		(at 472.86418 -27.0764 180)
		(property "Reference" "C22W11"
			(at 0 0 180)
			(layer "F.SilkS")
			(hide yes)
			(effects
				(font
					(size 1.27 1.27)
				)
			)
		)
		(property "Value" "*"
			(at -0.0762 -6.2357 180)
			(unlocked yes)
			(layer "F.Fab")
			(hide yes)
			(effects
				(font
					(size 1.27 1.016)
					(thickness 0.1524)
				)
			)
		)
		(property "Device Type" "SC22U16V5MX-4-GP_SMD-BCG5-SC22A"
			(at -0.0762 -8.2677 180)
			(unlocked yes)
			(layer "F.Fab")
			(hide yes)
			(effects
				(font
					(size 1.27 1.016)
					(thickness 0.1524)
				)
			)
		)
		(duplicate_pad_numbers_are_jumpers no)
		(fp_line
			(start 0.635 0)
			(end -0.635 0)
			(stroke
				(width 0.508)
				(type default)
			)
			(layer "F.SilkS")
		)
		(fp_rect
			(start -0.9652 1.778)
			(end 0.9652 -1.778)
			(stroke
				(width 0)
				(type default)
			)
			(fill no)
			(layer "F.CrtYd")
		)
		(fp_poly
			(pts
				(xy -0.9652 -1.778) (xy 0.9652 -1.778) (xy 0.9652 1.778) (xy -0.9652 1.778)
			)
			(stroke
				(width 0)
				(type default)
			)
			(fill no)
			(layer "F.Fab")
		)
		(pad "1" smd rect
			(at 0 -0.9652 180)
			(size 1.397 1.143)
			(layers "F.Cu" "F.Mask" "F.Paste")
			(net "VR_FET_SW_P12V_STBY_P3V3_STBY")
		)
		(pad "2" smd rect
			(at 0 0.9652 180)
			(size 1.397 1.143)
			(layers "F.Cu" "F.Mask" "F.Paste")
			(net "GND")
		)
	)
)
